# T6G (Grand Teton) — schematic netlist excerpt (pin names and nets, part order shuffled) for the footprints in the layout excerpt that follows; sources: Cadence DE-HDL packaged netlist, KiCad conversion of 04192023_DAF0TMB3IC0_F0TG_MB_C_brd_V02_OCP.brd

R6772  Q_RES  4.7K 5% EMPTY  pkg 0201LF  page 184 : A = P1V8_AUX ; B = RT_SMB_MUX_ADDR0
C2140  Q_CAP  22UF 4V 20% X6S  pkg C0402  page 68 : A = PVDDCR_SOC_P0 ; B = GND
C2655  Q_CAP  22UF 4V 20% X6S  pkg C0402  page 70 : A = PVDDIO_P0 ; B = GND

(kicad_pcb
	(version 20260206)
	(generator "pcbnew")
	(generator_version "10.0")
	(general
		(thickness 1.6)
		(legacy_teardrops no)
	)
	(paper "A4")
	(title_block
		(title "04192023_DAF0TMB3IC0_F0TG_MB_C_brd_V02_OCP.brd")
		(comment 1 "Grand Teton / footprints 6892-6894 of 8354")
	)
	(layers
		(0 "F.Cu" signal "TOP")
		(4 "In1.Cu" signal "GND")
		(6 "In2.Cu" signal "IN1")
		(8 "In3.Cu" signal "GND1")
		(10 "In4.Cu" signal "IN2")
		(12 "In5.Cu" signal "GND2")
		(14 "In6.Cu" signal "IN3")
		(16 "In7.Cu" signal "GND3")
		(18 "In8.Cu" signal "VCC")
		(20 "In9.Cu" signal "VCC1")
		(22 "In10.Cu" signal "GND4")
		(24 "In11.Cu" signal "IN4")
		(26 "In12.Cu" signal "GND5")
		(28 "In13.Cu" signal "IN5")
		(30 "In14.Cu" signal "GND6")
		(32 "In15.Cu" signal "IN6")
		(34 "In16.Cu" signal "GND7")
		(2 "B.Cu" signal "BOTTOM")
		(9 "F.Adhes" user "F.Adhesive")
		(11 "B.Adhes" user "B.Adhesive")
		(13 "F.Paste" user "Package Geometry/Pastemask Top")
		(15 "B.Paste" user "Package Geometry/Pastemask Bottom")
		(5 "F.SilkS" user "Ref Des/Silkscreen Top")
		(7 "B.SilkS" user "Ref Des/Silkscreen Bottom")
		(1 "F.Mask" user "Board Geometry/Soldermask Top")
		(3 "B.Mask" user "Board Geometry/Soldermask Bottom")
		(17 "Dwgs.User" user "User.Drawings")
		(19 "Cmts.User" user "User.Comments")
		(21 "Eco1.User" user "User.Eco1")
		(23 "Eco2.User" user "User.Eco2")
		(25 "Edge.Cuts" user "Board Geometry/Outline")
		(27 "Margin" user)
		(31 "F.CrtYd" user "Package Geometry/Place Bound Top")
		(29 "B.CrtYd" user "Package Geometry/Place Bound Bottom")
		(35 "F.Fab" user "Ref Des/Assembly Top")
		(33 "B.Fab" user "Ref Des/Assembly Bottom")
	)
	(footprint ""
		(layer "B.Cu")
		(at 359.721404 -254.44831 180)
		(property "Reference" "C2140"
			(at 0 0 0)
			(layer "B.SilkS")
			(hide yes)
			(effects
				(font
					(size 1.27 1.27)
				)
				(justify mirror)
			)
		)
		(property "Value" ""
			(at 0 0 0)
			(layer "B.Fab")
			(effects
				(font
					(size 1.27 1.27)
				)
				(justify mirror)
			)
		)
		(duplicate_pad_numbers_are_jumpers no)
		(fp_line
			(start 0.7874 0.4064)
			(end 0.7874 -0.4064)
			(stroke
				(width 0.1524)
				(type default)
			)
			(layer "B.SilkS")
		)
		(fp_line
			(start 0.7874 -0.4064)
			(end -0.7874 -0.4064)
			(stroke
				(width 0.1524)
				(type default)
			)
			(layer "B.SilkS")
		)
		(fp_line
			(start -0.7874 0.4064)
			(end 0.7874 0.4064)
			(stroke
				(width 0.1524)
				(type default)
			)
			(layer "B.SilkS")
		)
		(fp_line
			(start -0.7874 -0.4064)
			(end -0.7874 0.4064)
			(stroke
				(width 0.1524)
				(type default)
			)
			(layer "B.SilkS")
		)
		(fp_line
			(start 0.67945 0.3048)
			(end 0.67945 -0.305054)
			(stroke
				(width 0.1)
				(type default)
			)
			(layer "B.Fab")
		)
		(fp_line
			(start 0.67945 -0.305054)
			(end 0.12065 -0.305054)
			(stroke
				(width 0.1)
				(type default)
			)
			(layer "B.Fab")
		)
		(fp_line
			(start 0.12065 0.3048)
			(end 0.67945 0.3048)
			(stroke
				(width 0.1)
				(type default)
			)
			(layer "B.Fab")
		)
		(fp_line
			(start 0.12065 0.2794)
			(end 0.12065 0.3048)
			(stroke
				(width 0.1)
				(type default)
			)
			(layer "B.Fab")
		)
		(fp_line
			(start 0.12065 -0.2794)
			(end -0.12065 -0.2794)
			(stroke
				(width 0.1)
				(type default)
			)
			(layer "B.Fab")
		)
		(fp_line
			(start 0.12065 -0.305054)
			(end 0.12065 -0.2794)
			(stroke
				(width 0.1)
				(type default)
			)
			(layer "B.Fab")
		)
		(fp_line
			(start -0.120396 0.3048)
			(end -0.120396 0.2794)
			(stroke
				(width 0.1)
				(type default)
			)
			(layer "B.Fab")
		)
		(fp_line
			(start -0.120396 0.2794)
			(end 0.12065 0.2794)
			(stroke
				(width 0.1)
				(type default)
			)
			(layer "B.Fab")
		)
		(fp_line
			(start -0.12065 -0.2794)
			(end -0.12065 -0.3048)
			(stroke
				(width 0.1)
				(type default)
			)
			(layer "B.Fab")
		)
		(fp_line
			(start -0.12065 -0.3048)
			(end -0.67945 -0.3048)
			(stroke
				(width 0.1)
				(type default)
			)
			(layer "B.Fab")
		)
		(fp_line
			(start -0.67945 0.3048)
			(end -0.120396 0.3048)
			(stroke
				(width 0.1)
				(type default)
			)
			(layer "B.Fab")
		)
		(fp_line
			(start -0.67945 -0.3048)
			(end -0.67945 0.3048)
			(stroke
				(width 0.1)
				(type default)
			)
			(layer "B.Fab")
		)
		(pad "1" smd circle
			(at 0.40005 0)
			(size 0 0)
			(layers "B.Cu" "B.Mask" "B.Paste")
			(net "PVDDCR_SOC_P0")
		)
		(pad "2" smd circle
			(at -0.40005 0)
			(size 0 0)
			(layers "B.Cu" "B.Mask" "B.Paste")
			(net "GND")
		)
	)
	(footprint ""
		(layer "B.Cu")
		(at 217.17 -330.708 180)
		(property "Reference" "R6772"
			(at 0 0 0)
			(layer "B.SilkS")
			(hide yes)
			(effects
				(font
					(size 1.27 1.27)
				)
				(justify mirror)
			)
		)
		(property "Value" ""
			(at 0 0 0)
			(layer "B.Fab")
			(effects
				(font
					(size 1.27 1.27)
				)
				(justify mirror)
			)
		)
		(duplicate_pad_numbers_are_jumpers no)
		(fp_line
			(start 0.32512 0.175006)
			(end 0.32512 -0.175006)
			(stroke
				(width 0.1)
				(type default)
			)
			(layer "B.Fab")
		)
		(fp_line
			(start 0.32512 -0.175006)
			(end -0.32512 -0.175006)
			(stroke
				(width 0.1)
				(type default)
			)
			(layer "B.Fab")
		)
		(fp_line
			(start -0.32512 0.175006)
			(end 0.32512 0.175006)
			(stroke
				(width 0.1)
				(type default)
			)
			(layer "B.Fab")
		)
		(fp_line
			(start -0.32512 -0.175006)
			(end -0.32512 0.175006)
			(stroke
				(width 0.1)
				(type default)
			)
			(layer "B.Fab")
		)
		(pad "1" smd rect
			(at 0.2667 0)
			(size 0.3048 0.381)
			(layers "B.Cu" "B.Mask" "B.Paste")
			(net "P1V8_AUX")
		)
		(pad "2" smd rect
			(at -0.2667 0 180)
			(size 0.3048 0.381)
			(layers "B.Cu" "B.Mask" "B.Paste")
			(net "RT_SMB_MUX_ADDR0")
		)
	)
	(footprint ""
		(layer "B.Cu")
		(at 346.518992 -259.729986 180)
		(property "Reference" "C2655"
			(at 0 0 0)
			(layer "B.SilkS")
			(hide yes)
			(effects
				(font
					(size 1.27 1.27)
				)
				(justify mirror)
			)
		)
		(property "Value" ""
			(at 0 0 0)
			(layer "B.Fab")
			(effects
				(font
					(size 1.27 1.27)
				)
				(justify mirror)
			)
		)
		(duplicate_pad_numbers_are_jumpers no)
		(fp_line
			(start 0.7874 0.4064)
			(end 0.7874 -0.4064)
			(stroke
				(width 0.1524)
				(type default)
			)
			(layer "B.SilkS")
		)
		(fp_line
			(start 0.7874 -0.4064)
			(end -0.7874 -0.4064)
			(stroke
				(width 0.1524)
				(type default)
			)
			(layer "B.SilkS")
		)
		(fp_line
			(start -0.7874 0.4064)
			(end 0.7874 0.4064)
			(stroke
				(width 0.1524)
				(type default)
			)
			(layer "B.SilkS")
		)
		(fp_line
			(start -0.7874 -0.4064)
			(end -0.7874 0.4064)
			(stroke
				(width 0.1524)
				(type default)
			)
			(layer "B.SilkS")
		)
		(fp_line
			(start 0.67945 0.3048)
			(end 0.67945 -0.305054)
			(stroke
				(width 0.1)
				(type default)
			)
			(layer "B.Fab")
		)
		(fp_line
			(start 0.67945 -0.305054)
			(end 0.12065 -0.305054)
			(stroke
				(width 0.1)
				(type default)
			)
			(layer "B.Fab")
		)
		(fp_line
			(start 0.12065 0.3048)
			(end 0.67945 0.3048)
			(stroke
				(width 0.1)
				(type default)
			)
			(layer "B.Fab")
		)
		(fp_line
			(start 0.12065 0.2794)
			(end 0.12065 0.3048)
			(stroke
				(width 0.1)
				(type default)
			)
			(layer "B.Fab")
		)
		(fp_line
			(start 0.12065 -0.2794)
			(end -0.12065 -0.2794)
			(stroke
				(width 0.1)
				(type default)
			)
			(layer "B.Fab")
		)
		(fp_line
			(start 0.12065 -0.305054)
			(end 0.12065 -0.2794)
			(stroke
				(width 0.1)
				(type default)
			)
			(layer "B.Fab")
		)
		(fp_line
			(start -0.120396 0.3048)
			(end -0.120396 0.2794)
			(stroke
				(width 0.1)
				(type default)
			)
			(layer "B.Fab")
		)
		(fp_line
			(start -0.120396 0.2794)
			(end 0.12065 0.2794)
			(stroke
				(width 0.1)
				(type default)
			)
			(layer "B.Fab")
		)
		(fp_line
			(start -0.12065 -0.2794)
			(end -0.12065 -0.3048)
			(stroke
				(width 0.1)
				(type default)
			)
			(layer "B.Fab")
		)
		(fp_line
			(start -0.12065 -0.3048)
			(end -0.67945 -0.3048)
			(stroke
				(width 0.1)
				(type default)
			)
			(layer "B.Fab")
		)
		(fp_line
			(start -0.67945 0.3048)
			(end -0.120396 0.3048)
			(stroke
				(width 0.1)
				(type default)
			)
			(layer "B.Fab")
		)
		(fp_line
			(start -0.67945 -0.3048)
			(end -0.67945 0.3048)
			(stroke
				(width 0.1)
				(type default)
			)
			(layer "B.Fab")
		)
		(pad "1" smd circle
			(at 0.40005 0)
			(size 0 0)
			(layers "B.Cu" "B.Mask" "B.Paste")
			(net "PVDDIO_P0")
		)
		(pad "2" smd circle
			(at -0.40005 0)
			(size 0 0)
			(layers "B.Cu" "B.Mask" "B.Paste")
			(net "GND")
		)
	)
)
